(kicad_pcb
	(version 20260206)
	(generator "pcbnew")
	(generator_version "10.0")
	(general
		(thickness 1.6)
		(legacy_teardrops no)
	)
	(paper "A4")
	(title_block
		(title "04192023_DAF0TMB3IC0_F0TG_MB_C_brd_V02_OCP.brd")
		(comment 1 "Grand Teton / footprints 2299-2306 of 8354")
	)
	(layers
		(0 "F.Cu" signal "TOP")
		(4 "In1.Cu" signal "GND")
		(6 "In2.Cu" signal "IN1")
		(8 "In3.Cu" signal "GND1")
		(10 "In4.Cu" signal "IN2")
		(12 "In5.Cu" signal "GND2")
		(14 "In6.Cu" signal "IN3")
		(16 "In7.Cu" signal "GND3")
		(18 "In8.Cu" signal "VCC")
		(20 "In9.Cu" signal "VCC1")
		(22 "In10.Cu" signal "GND4")
		(24 "In11.Cu" signal "IN4")
		(26 "In12.Cu" signal "GND5")
		(28 "In13.Cu" signal "IN5")
		(30 "In14.Cu" signal "GND6")
		(32 "In15.Cu" signal "IN6")
		(34 "In16.Cu" signal "GND7")
		(2 "B.Cu" signal "BOTTOM")
		(9 "F.Adhes" user "F.Adhesive")
		(11 "B.Adhes" user "B.Adhesive")
		(13 "F.Paste" user "Package Geometry/Pastemask Top")
		(15 "B.Paste" user "Package Geometry/Pastemask Bottom")
		(5 "F.SilkS" user "Ref Des/Silkscreen Top")
		(7 "B.SilkS" user "Ref Des/Silkscreen Bottom")
		(1 "F.Mask" user "Board Geometry/Soldermask Top")
		(3 "B.Mask" user "Board Geometry/Soldermask Bottom")
		(17 "Dwgs.User" user "User.Drawings")
		(19 "Cmts.User" user "User.Comments")
		(21 "Eco1.User" user "User.Eco1")
		(23 "Eco2.User" user "User.Eco2")
		(25 "Edge.Cuts" user "Board Geometry/Outline")
		(27 "Margin" user)
		(31 "F.CrtYd" user "Package Geometry/Place Bound Top")
		(29 "B.CrtYd" user "Package Geometry/Place Bound Bottom")
		(35 "F.Fab" user "Ref Des/Assembly Top")
		(33 "B.Fab" user "Ref Des/Assembly Bottom")
	)
	(footprint ""
		(layer "F.Cu")
		(at 265.16838 -419.628828)
		(property "Reference" "R3923"
			(at 0 0 0)
			(layer "F.SilkS")
			(hide yes)
			(effects
				(font
					(size 1.27 1.27)
				)
			)
		)
		(property "Value" ""
			(at 0 0 0)
			(layer "F.Fab")
			(effects
				(font
					(size 1.27 1.27)
				)
			)
		)
		(duplicate_pad_numbers_are_jumpers no)
		(fp_line
			(start -0.7874 -0.4064)
			(end 0.7874 -0.4064)
			(stroke
				(width 0.1524)
				(type default)
			)
			(layer "F.SilkS")
		)
		(fp_line
			(start -0.7874 0.4064)
			(end -0.7874 -0.4064)
			(stroke
				(width 0.1524)
				(type default)
			)
			(layer "F.SilkS")
		)
		(fp_line
			(start 0.7874 -0.4064)
			(end 0.7874 0.4064)
			(stroke
				(width 0.1524)
				(type default)
			)
			(layer "F.SilkS")
		)
		(fp_line
			(start 0.7874 0.4064)
			(end -0.7874 0.4064)
			(stroke
				(width 0.1524)
				(type default)
			)
			(layer "F.SilkS")
		)
		(fp_line
			(start -0.67945 -0.305054)
			(end -0.12065 -0.305054)
			(stroke
				(width 0.1)
				(type default)
			)
			(layer "F.Fab")
		)
		(fp_line
			(start -0.67945 0.3048)
			(end -0.67945 -0.305054)
			(stroke
				(width 0.1)
				(type default)
			)
			(layer "F.Fab")
		)
		(fp_line
			(start -0.12065 -0.305054)
			(end -0.12065 -0.2794)
			(stroke
				(width 0.1)
				(type default)
			)
			(layer "F.Fab")
		)
		(fp_line
			(start -0.12065 -0.2794)
			(end 0.12065 -0.2794)
			(stroke
				(width 0.1)
				(type default)
			)
			(layer "F.Fab")
		)
		(fp_line
			(start -0.12065 0.2794)
			(end -0.12065 0.3048)
			(stroke
				(width 0.1)
				(type default)
			)
			(layer "F.Fab")
		)
		(fp_line
			(start -0.12065 0.3048)
			(end -0.67945 0.3048)
			(stroke
				(width 0.1)
				(type default)
			)
			(layer "F.Fab")
		)
		(fp_line
			(start 0.120396 0.2794)
			(end -0.12065 0.2794)
			(stroke
				(width 0.1)
				(type default)
			)
			(layer "F.Fab")
		)
		(fp_line
			(start 0.120396 0.3048)
			(end 0.120396 0.2794)
			(stroke
				(width 0.1)
				(type default)
			)
			(layer "F.Fab")
		)
		(fp_line
			(start 0.12065 -0.3048)
			(end 0.67945 -0.3048)
			(stroke
				(width 0.1)
				(type default)
			)
			(layer "F.Fab")
		)
		(fp_line
			(start 0.12065 -0.2794)
			(end 0.12065 -0.3048)
			(stroke
				(width 0.1)
				(type default)
			)
			(layer "F.Fab")
		)
		(fp_line
			(start 0.67945 -0.3048)
			(end 0.67945 0.3048)
			(stroke
				(width 0.1)
				(type default)
			)
			(layer "F.Fab")
		)
		(fp_line
			(start 0.67945 0.3048)
			(end 0.120396 0.3048)
			(stroke
				(width 0.1)
				(type default)
			)
			(layer "F.Fab")
		)
		(pad "1" smd circle
			(at -0.40005 0)
			(size 0 0)
			(layers "F.Cu" "F.Mask" "F.Paste")
			(net "P12V_PSU_FUSE")
		)
		(pad "2" smd circle
			(at 0.40005 0)
			(size 0 0)
			(layers "F.Cu" "F.Mask" "F.Paste")
			(net "PDB_PRSNT_R_N")
		)
	)
	(footprint ""
		(layer "F.Cu")
		(at 279.513792 -114.64417 180)
		(property "Reference" "R3527"
			(at 0 0 180)
			(layer "F.SilkS")
			(hide yes)
			(effects
				(font
					(size 1.27 1.27)
				)
			)
		)
		(property "Value" ""
			(at 0 0 180)
			(layer "F.Fab")
			(effects
				(font
					(size 1.27 1.27)
				)
			)
		)
		(duplicate_pad_numbers_are_jumpers no)
		(fp_line
			(start 0.7874 0.4064)
			(end -0.7874 0.4064)
			(stroke
				(width 0.1524)
				(type default)
			)
			(layer "F.SilkS")
		)
		(fp_line
			(start 0.7874 -0.4064)
			(end 0.7874 0.4064)
			(stroke
				(width 0.1524)
				(type default)
			)
			(layer "F.SilkS")
		)
		(fp_line
			(start -0.7874 0.4064)
			(end -0.7874 -0.4064)
			(stroke
				(width 0.1524)
				(type default)
			)
			(layer "F.SilkS")
		)
		(fp_line
			(start -0.7874 -0.4064)
			(end 0.7874 -0.4064)
			(stroke
				(width 0.1524)
				(type default)
			)
			(layer "F.SilkS")
		)
		(fp_line
			(start 0.67945 0.3048)
			(end 0.120396 0.3048)
			(stroke
				(width 0.1)
				(type default)
			)
			(layer "F.Fab")
		)
		(fp_line
			(start 0.67945 -0.3048)
			(end 0.67945 0.3048)
			(stroke
				(width 0.1)
				(type default)
			)
			(layer "F.Fab")
		)
		(fp_line
			(start 0.12065 -0.2794)
			(end 0.12065 -0.3048)
			(stroke
				(width 0.1)
				(type default)
			)
			(layer "F.Fab")
		)
		(fp_line
			(start 0.12065 -0.3048)
			(end 0.67945 -0.3048)
			(stroke
				(width 0.1)
				(type default)
			)
			(layer "F.Fab")
		)
		(fp_line
			(start 0.120396 0.3048)
			(end 0.120396 0.2794)
			(stroke
				(width 0.1)
				(type default)
			)
			(layer "F.Fab")
		)
		(fp_line
			(start 0.120396 0.2794)
			(end -0.12065 0.2794)
			(stroke
				(width 0.1)
				(type default)
			)
			(layer "F.Fab")
		)
		(fp_line
			(start -0.12065 0.3048)
			(end -0.67945 0.3048)
			(stroke
				(width 0.1)
				(type default)
			)
			(layer "F.Fab")
		)
		(fp_line
			(start -0.12065 0.2794)
			(end -0.12065 0.3048)
			(stroke
				(width 0.1)
				(type default)
			)
			(layer "F.Fab")
		)
		(fp_line
			(start -0.12065 -0.2794)
			(end 0.12065 -0.2794)
			(stroke
				(width 0.1)
				(type default)
			)
			(layer "F.Fab")
		)
		(fp_line
			(start -0.12065 -0.305054)
			(end -0.12065 -0.2794)
			(stroke
				(width 0.1)
				(type default)
			)
			(layer "F.Fab")
		)
		(fp_line
			(start -0.67945 0.3048)
			(end -0.67945 -0.305054)
			(stroke
				(width 0.1)
				(type default)
			)
			(layer "F.Fab")
		)
		(fp_line
			(start -0.67945 -0.305054)
			(end -0.12065 -0.305054)
			(stroke
				(width 0.1)
				(type default)
			)
			(layer "F.Fab")
		)
		(pad "1" smd circle
			(at -0.40005 0 180)
			(size 0 0)
			(layers "F.Cu" "F.Mask" "F.Paste")
			(net "SMB_PCIE0_3V3AUX_SDA_R5")
		)
		(pad "2" smd circle
			(at 0.40005 0 180)
			(size 0 0)
			(layers "F.Cu" "F.Mask" "F.Paste")
			(net "SMB_SENSOR_E1S_3V3AUX_SDA")
		)
	)
	(footprint ""
		(layer "F.Cu")
		(at 447.237866 -407.6573 180)
		(property "Reference" "PC6559_1"
			(at 0 0 180)
			(layer "F.SilkS")
			(hide yes)
			(effects
				(font
					(size 1.27 1.27)
				)
			)
		)
		(property "Value" ""
			(at 0 0 180)
			(layer "F.Fab")
			(effects
				(font
					(size 1.27 1.27)
				)
			)
		)
		(duplicate_pad_numbers_are_jumpers no)
		(fp_line
			(start 1.524 0.762)
			(end -1.524 0.762)
			(stroke
				(width 0.1524)
				(type default)
			)
			(layer "F.SilkS")
		)
		(fp_line
			(start 1.524 -0.762)
			(end 1.524 0.762)
			(stroke
				(width 0.1524)
				(type default)
			)
			(layer "F.SilkS")
		)
		(fp_line
			(start -1.524 0.762)
			(end -1.524 -0.762)
			(stroke
				(width 0.1524)
				(type default)
			)
			(layer "F.SilkS")
		)
		(fp_line
			(start -1.524 -0.762)
			(end 1.524 -0.762)
			(stroke
				(width 0.1524)
				(type default)
			)
			(layer "F.SilkS")
		)
		(fp_line
			(start 1.1049 0.724916)
			(end 1.1049 -0.724916)
			(stroke
				(width 0.1)
				(type default)
			)
			(layer "F.Fab")
		)
		(fp_line
			(start 1.1049 -0.724916)
			(end -1.1049 -0.724916)
			(stroke
				(width 0.1)
				(type default)
			)
			(layer "F.Fab")
		)
		(fp_line
			(start -1.1049 0.724916)
			(end 1.1049 0.724916)
			(stroke
				(width 0.1)
				(type default)
			)
			(layer "F.Fab")
		)
		(fp_line
			(start -1.1049 -0.724916)
			(end -1.1049 0.724916)
			(stroke
				(width 0.1)
				(type default)
			)
			(layer "F.Fab")
		)
		(pad "1" smd rect
			(at -0.889 0)
			(size 1.016 1.27)
			(layers "F.Cu" "F.Mask" "F.Paste")
			(net "SW_P12V_AUX_P0V9_RETIMER_CPU0_FLT")
		)
		(pad "2" smd rect
			(at 0.889 0)
			(size 1.016 1.27)
			(layers "F.Cu" "F.Mask" "F.Paste")
			(net "GND")
		)
	)
	(footprint ""
		(layer "F.Cu")
		(at 15.527782 -416.050984 90)
		(property "Reference" "PR6539"
			(at 0 0 90)
			(layer "F.SilkS")
			(hide yes)
			(effects
				(font
					(size 1.27 1.27)
				)
			)
		)
		(property "Value" ""
			(at 0 0 90)
			(layer "F.Fab")
			(effects
				(font
					(size 1.27 1.27)
				)
			)
		)
		(duplicate_pad_numbers_are_jumpers no)
		(fp_line
			(start 0.7874 -0.4064)
			(end 0.7874 0.4064)
			(stroke
				(width 0.1524)
				(type default)
			)
			(layer "F.SilkS")
		)
		(fp_line
			(start -0.7874 -0.4064)
			(end 0.7874 -0.4064)
			(stroke
				(width 0.1524)
				(type default)
			)
			(layer "F.SilkS")
		)
		(fp_line
			(start 0.7874 0.4064)
			(end -0.7874 0.4064)
			(stroke
				(width 0.1524)
				(type default)
			)
			(layer "F.SilkS")
		)
		(fp_line
			(start -0.7874 0.4064)
			(end -0.7874 -0.4064)
			(stroke
				(width 0.1524)
				(type default)
			)
			(layer "F.SilkS")
		)
		(fp_line
			(start -0.12065 -0.305054)
			(end -0.12065 -0.2794)
			(stroke
				(width 0.1)
				(type default)
			)
			(layer "F.Fab")
		)
		(fp_line
			(start -0.67945 -0.305054)
			(end -0.12065 -0.305054)
			(stroke
				(width 0.1)
				(type default)
			)
			(layer "F.Fab")
		)
		(fp_line
			(start 0.67945 -0.3048)
			(end 0.67945 0.3048)
			(stroke
				(width 0.1)
				(type default)
			)
			(layer "F.Fab")
		)
		(fp_line
			(start 0.12065 -0.3048)
			(end 0.67945 -0.3048)
			(stroke
				(width 0.1)
				(type default)
			)
			(layer "F.Fab")
		)
		(fp_line
			(start 0.12065 -0.2794)
			(end 0.12065 -0.3048)
			(stroke
				(width 0.1)
				(type default)
			)
			(layer "F.Fab")
		)
		(fp_line
			(start -0.12065 -0.2794)
			(end 0.12065 -0.2794)
			(stroke
				(width 0.1)
				(type default)
			)
			(layer "F.Fab")
		)
		(fp_line
			(start 0.120396 0.2794)
			(end -0.12065 0.2794)
			(stroke
				(width 0.1)
				(type default)
			)
			(layer "F.Fab")
		)
		(fp_line
			(start -0.12065 0.2794)
			(end -0.12065 0.3048)
			(stroke
				(width 0.1)
				(type default)
			)
			(layer "F.Fab")
		)
		(fp_line
			(start 0.67945 0.3048)
			(end 0.120396 0.3048)
			(stroke
				(width 0.1)
				(type default)
			)
			(layer "F.Fab")
		)
		(fp_line
			(start 0.120396 0.3048)
			(end 0.120396 0.2794)
			(stroke
				(width 0.1)
				(type default)
			)
			(layer "F.Fab")
		)
		(fp_line
			(start -0.12065 0.3048)
			(end -0.67945 0.3048)
			(stroke
				(width 0.1)
				(type default)
			)
			(layer "F.Fab")
		)
		(fp_line
			(start -0.67945 0.3048)
			(end -0.67945 -0.305054)
			(stroke
				(width 0.1)
				(type default)
			)
			(layer "F.Fab")
		)
		(pad "1" smd circle
			(at -0.40005 0 90)
			(size 0 0)
			(layers "F.Cu" "F.Mask" "F.Paste")
			(net "NC_P0V9_RETIMER_CPU1_IMON3")
		)
		(pad "2" smd circle
			(at 0.40005 0 90)
			(size 0 0)
			(layers "F.Cu" "F.Mask" "F.Paste")
			(net "GND")
		)
	)
	(footprint ""
		(layer "F.Cu")
		(at 400.315684 -403.818852 -90)
		(property "Reference" "R1065"
			(at 0 0 270)
			(layer "F.SilkS")
			(hide yes)
			(effects
				(font
					(size 1.27 1.27)
				)
			)
		)
		(property "Value" ""
			(at 0 0 270)
			(layer "F.Fab")
			(effects
				(font
					(size 1.27 1.27)
				)
			)
		)
		(duplicate_pad_numbers_are_jumpers no)
		(fp_line
			(start -0.32512 0.175006)
			(end -0.32512 -0.175006)
			(stroke
				(width 0.1)
				(type default)
			)
			(layer "F.Fab")
		)
		(fp_line
			(start 0.32512 0.175006)
			(end -0.32512 0.175006)
			(stroke
				(width 0.1)
				(type default)
			)
			(layer "F.Fab")
		)
		(fp_line
			(start -0.32512 -0.175006)
			(end 0.32512 -0.175006)
			(stroke
				(width 0.1)
				(type default)
			)
			(layer "F.Fab")
		)
		(fp_line
			(start 0.32512 -0.175006)
			(end 0.32512 0.175006)
			(stroke
				(width 0.1)
				(type default)
			)
			(layer "F.Fab")
		)
		(pad "1" smd rect
			(at -0.2667 0 270)
			(size 0.3048 0.381)
			(layers "F.Cu" "F.Mask" "F.Paste")
			(net "P1V8_CPU0_RT_1D")
		)
		(pad "2" smd rect
			(at 0.2667 0 90)
			(size 0.3048 0.381)
			(layers "F.Cu" "F.Mask" "F.Paste")
			(net "RST_RT_CPU0_P2_RESET_R_N")
		)
	)
	(footprint ""
		(layer "F.Cu")
		(at 314.66282 -337.660488 90)
		(property "Reference" "PC110"
			(at 0 0 90)
			(layer "F.SilkS")
			(hide yes)
			(effects
				(font
					(size 1.27 1.27)
				)
			)
		)
		(property "Value" ""
			(at 0 0 90)
			(layer "F.Fab")
			(effects
				(font
					(size 1.27 1.27)
				)
			)
		)
		(duplicate_pad_numbers_are_jumpers no)
		(fp_line
			(start 0.7874 -0.4064)
			(end 0.7874 0.4064)
			(stroke
				(width 0.1524)
				(type default)
			)
			(layer "F.SilkS")
		)
		(fp_line
			(start -0.7874 -0.4064)
			(end 0.7874 -0.4064)
			(stroke
				(width 0.1524)
				(type default)
			)
			(layer "F.SilkS")
		)
		(fp_line
			(start 0.7874 0.4064)
			(end 0.413512 0.4064)
			(stroke
				(width 0.1524)
				(type default)
			)
			(layer "F.SilkS")
		)
		(fp_line
			(start -0.272288 0.4064)
			(end -0.7874 0.4064)
			(stroke
				(width 0.1524)
				(type default)
			)
			(layer "F.SilkS")
		)
		(fp_line
			(start -0.7874 0.4064)
			(end -0.7874 -0.4064)
			(stroke
				(width 0.1524)
				(type default)
			)
			(layer "F.SilkS")
		)
		(fp_line
			(start -0.12065 -0.305054)
			(end -0.12065 -0.2794)
			(stroke
				(width 0.1)
				(type default)
			)
			(layer "F.Fab")
		)
		(fp_line
			(start -0.67945 -0.305054)
			(end -0.12065 -0.305054)
			(stroke
				(width 0.1)
				(type default)
			)
			(layer "F.Fab")
		)
		(fp_line
			(start 0.67945 -0.3048)
			(end 0.67945 0.3048)
			(stroke
				(width 0.1)
				(type default)
			)
			(layer "F.Fab")
		)
		(fp_line
			(start 0.12065 -0.3048)
			(end 0.67945 -0.3048)
			(stroke
				(width 0.1)
				(type default)
			)
			(layer "F.Fab")
		)
		(fp_line
			(start 0.12065 -0.2794)
			(end 0.12065 -0.3048)
			(stroke
				(width 0.1)
				(type default)
			)
			(layer "F.Fab")
		)
		(fp_line
			(start -0.12065 -0.2794)
			(end 0.12065 -0.2794)
			(stroke
				(width 0.1)
				(type default)
			)
			(layer "F.Fab")
		)
		(fp_line
			(start 0.120396 0.2794)
			(end -0.12065 0.2794)
			(stroke
				(width 0.1)
				(type default)
			)
			(layer "F.Fab")
		)
		(fp_line
			(start -0.12065 0.2794)
			(end -0.12065 0.3048)
			(stroke
				(width 0.1)
				(type default)
			)
			(layer "F.Fab")
		)
		(fp_line
			(start 0.67945 0.3048)
			(end 0.120396 0.3048)
			(stroke
				(width 0.1)
				(type default)
			)
			(layer "F.Fab")
		)
		(fp_line
			(start 0.120396 0.3048)
			(end 0.120396 0.2794)
			(stroke
				(width 0.1)
				(type default)
			)
			(layer "F.Fab")
		)
		(fp_line
			(start -0.12065 0.3048)
			(end -0.67945 0.3048)
			(stroke
				(width 0.1)
				(type default)
			)
			(layer "F.Fab")
		)
		(fp_line
			(start -0.67945 0.3048)
			(end -0.67945 -0.305054)
			(stroke
				(width 0.1)
				(type default)
			)
			(layer "F.Fab")
		)
		(pad "1" smd circle
			(at -0.40005 0 90)
			(size 0 0)
			(layers "F.Cu" "F.Mask" "F.Paste")
			(net "PVDDCR_CPU1_P0_VCC3")
		)
		(pad "2" smd circle
			(at 0.40005 0 90)
			(size 0 0)
			(layers "F.Cu" "F.Mask" "F.Paste")
			(net "GND")
		)
	)
	(footprint ""
		(layer "F.Cu")
		(at 324.516496 -378.95403 -90)
		(property "Reference" "C906"
			(at 0 0 270)
			(layer "F.SilkS")
			(hide yes)
			(effects
				(font
					(size 1.27 1.27)
				)
			)
		)
		(property "Value" ""
			(at 0 0 270)
			(layer "F.Fab")
			(effects
				(font
					(size 1.27 1.27)
				)
			)
		)
		(duplicate_pad_numbers_are_jumpers no)
		(fp_line
			(start -0.299974 0.150114)
			(end -0.299974 -0.150114)
			(stroke
				(width 0.1)
				(type default)
			)
			(layer "F.Fab")
		)
		(fp_line
			(start 0.299974 0.150114)
			(end -0.299974 0.150114)
			(stroke
				(width 0.1)
				(type default)
			)
			(layer "F.Fab")
		)
		(fp_line
			(start -0.299974 -0.150114)
			(end 0.299974 -0.150114)
			(stroke
				(width 0.1)
				(type default)
			)
			(layer "F.Fab")
		)
		(fp_line
			(start 0.299974 -0.150114)
			(end 0.299974 0.150114)
			(stroke
				(width 0.1)
				(type default)
			)
			(layer "F.Fab")
		)
		(pad "1" smd rect
			(at -0.2667 0 270)
			(size 0.3048 0.381)
			(layers "F.Cu" "F.Mask" "F.Paste")
			(net "P5E_CPU0_P0_TX_C_DN<13>")
		)
		(pad "2" smd rect
			(at 0.2667 0 270)
			(size 0.3048 0.381)
			(layers "F.Cu" "F.Mask" "F.Paste")
			(net "P5E_CPU0_P0_TX_DN<13>")
		)
	)
	(footprint ""
		(layer "F.Cu")
		(at 241.403378 -315.82868 90)
		(property "Reference" "PC6513"
			(at -1.75768 9.956292 90)
			(unlocked yes)
			(layer "F.SilkS")
			(effects
				(font
					(size 0.7874 0.5842)
					(thickness 0.1524)
				)
				(justify left)
			)
		)
		(property "Value" ""
			(at 0 0 90)
			(layer "F.Fab")
			(effects
				(font
					(size 1.27 1.27)
				)
			)
		)
		(duplicate_pad_numbers_are_jumpers no)
		(fp_line
			(start 2.750058 -2.750058)
			(end -1.988058 -2.750058)
			(stroke
				(width 0.1524)
				(type default)
			)
			(layer "F.SilkS")
		)
		(fp_line
			(start -1.988058 -2.750058)
			(end -2.750058 -1.988058)
			(stroke
				(width 0.1524)
				(type default)
			)
			(layer "F.SilkS")
		)
		(fp_line
			(start -2.750058 -1.988058)
			(end -2.750058 -0.9398)
			(stroke
				(width 0.1524)
				(type default)
			)
			(layer "F.SilkS")
		)
		(fp_line
			(start 2.750058 -0.9398)
			(end 2.750058 -2.750058)
			(stroke
				(width 0.1524)
				(type default)
			)
			(layer "F.SilkS")
		)
		(fp_line
			(start -2.750058 0.9398)
			(end -2.750058 1.988058)
			(stroke
				(width 0.1524)
				(type default)
			)
			(layer "F.SilkS")
		)
		(fp_line
			(start -2.750058 1.988058)
			(end -1.988058 2.750058)
			(stroke
				(width 0.1524)
				(type default)
			)
			(layer "F.SilkS")
		)
		(fp_line
			(start 2.750058 2.750058)
			(end 2.750058 0.9398)
			(stroke
				(width 0.1524)
				(type default)
			)
			(layer "F.SilkS")
		)
		(fp_line
			(start -1.988058 2.750058)
			(end 2.750058 2.750058)
			(stroke
				(width 0.1524)
				(type default)
			)
			(layer "F.SilkS")
		)
		(fp_line
			(start 2.750058 -2.750058)
			(end -2.750058 -2.750058)
			(stroke
				(width 0.1)
				(type default)
			)
			(layer "F.Fab")
		)
		(fp_line
			(start -2.750058 -2.750058)
			(end -2.750058 2.750058)
			(stroke
				(width 0.1)
				(type default)
			)
			(layer "F.Fab")
		)
		(fp_line
			(start 2.750058 2.750058)
			(end 2.750058 -2.750058)
			(stroke
				(width 0.1)
				(type default)
			)
			(layer "F.Fab")
		)
		(fp_line
			(start -2.750058 2.750058)
			(end 2.750058 2.750058)
			(stroke
				(width 0.1)
				(type default)
			)
			(layer "F.Fab")
		)
		(pad "1" smd rect
			(at -2.199894 0 180)
			(size 1.6002 3.0226)
			(layers "F.Cu" "F.Mask" "F.Paste")
			(net "P1V8_CPU0_RT_1D")
		)
		(pad "2" smd rect
			(at 2.199894 0 180)
			(size 1.6002 3.0226)
			(layers "F.Cu" "F.Mask" "F.Paste")
			(net "GND")
		)
	)
)
